(kicad_pcb
	(version 20260206)
	(generator "pcbnew")
	(generator_version "10.0")
	(general
		(thickness 1.6)
		(legacy_teardrops no)
	)
	(paper "A4")
	(title_block
		(title "01162023_DA0F0TEBIF0_F0T_Expander_BD_F_brd_V02_OCP.brd")
		(comment 1 "Grand Teton / footprints 5085-5091 of 9728")
	)
	(layers
		(0 "F.Cu" signal "TOP")
		(4 "In1.Cu" signal "GND")
		(6 "In2.Cu" signal "VCC")
		(8 "In3.Cu" signal "VCC1")
		(10 "In4.Cu" signal "GND1")
		(12 "In5.Cu" signal "IN1")
		(14 "In6.Cu" signal "GND2")
		(16 "In7.Cu" signal "IN2")
		(18 "In8.Cu" signal "GND3")
		(20 "In9.Cu" signal "IN3")
		(22 "In10.Cu" signal "GND4")
		(24 "In11.Cu" signal "IN4")
		(26 "In12.Cu" signal "GND5")
		(28 "In13.Cu" signal "IN5")
		(30 "In14.Cu" signal "GND6")
		(32 "In15.Cu" signal "IN6")
		(34 "In16.Cu" signal "GND7")
		(2 "B.Cu" signal "BOTTOM")
		(9 "F.Adhes" user "F.Adhesive")
		(11 "B.Adhes" user "B.Adhesive")
		(13 "F.Paste" user "Package Geometry/Pastemask Top")
		(15 "B.Paste" user "Package Geometry/Pastemask Bottom")
		(5 "F.SilkS" user "Ref Des/Silkscreen Top")
		(7 "B.SilkS" user "Ref Des/Silkscreen Bottom")
		(1 "F.Mask" user "Board Geometry/Soldermask Top")
		(3 "B.Mask" user "Board Geometry/Soldermask Bottom")
		(17 "Dwgs.User" user "User.Drawings")
		(19 "Cmts.User" user "User.Comments")
		(21 "Eco1.User" user "User.Eco1")
		(23 "Eco2.User" user "User.Eco2")
		(25 "Edge.Cuts" user "Board Geometry/Outline")
		(27 "Margin" user)
		(31 "F.CrtYd" user "Package Geometry/Place Bound Top")
		(29 "B.CrtYd" user "Package Geometry/Place Bound Bottom")
		(35 "F.Fab" user "Ref Des/Assembly Top")
		(33 "B.Fab" user "Ref Des/Assembly Bottom")
	)
	(footprint ""
		(layer "F.Cu")
		(at 459.31328 -258.331208 -90)
		(property "Reference" "R6556"
			(at 0 0 270)
			(layer "F.SilkS")
			(hide yes)
			(effects
				(font
					(size 1.27 1.27)
				)
			)
		)
		(property "Value" ""
			(at 0 0 270)
			(layer "F.Fab")
			(effects
				(font
					(size 1.27 1.27)
				)
			)
		)
		(duplicate_pad_numbers_are_jumpers no)
		(fp_line
			(start -0.7874 0.4064)
			(end -0.7874 -0.4064)
			(stroke
				(width 0.1524)
				(type default)
			)
			(layer "F.SilkS")
		)
		(fp_line
			(start 0.7874 0.4064)
			(end -0.7874 0.4064)
			(stroke
				(width 0.1524)
				(type default)
			)
			(layer "F.SilkS")
		)
		(fp_line
			(start -0.7874 -0.4064)
			(end 0.7874 -0.4064)
			(stroke
				(width 0.1524)
				(type default)
			)
			(layer "F.SilkS")
		)
		(fp_line
			(start 0.7874 -0.4064)
			(end 0.7874 0.4064)
			(stroke
				(width 0.1524)
				(type default)
			)
			(layer "F.SilkS")
		)
		(fp_line
			(start -0.67945 0.3048)
			(end -0.67945 -0.305054)
			(stroke
				(width 0.1)
				(type default)
			)
			(layer "F.Fab")
		)
		(fp_line
			(start -0.12065 0.3048)
			(end -0.67945 0.3048)
			(stroke
				(width 0.1)
				(type default)
			)
			(layer "F.Fab")
		)
		(fp_line
			(start 0.120396 0.3048)
			(end 0.120396 0.2794)
			(stroke
				(width 0.1)
				(type default)
			)
			(layer "F.Fab")
		)
		(fp_line
			(start 0.67945 0.3048)
			(end 0.120396 0.3048)
			(stroke
				(width 0.1)
				(type default)
			)
			(layer "F.Fab")
		)
		(fp_line
			(start -0.12065 0.2794)
			(end -0.12065 0.3048)
			(stroke
				(width 0.1)
				(type default)
			)
			(layer "F.Fab")
		)
		(fp_line
			(start 0.120396 0.2794)
			(end -0.12065 0.2794)
			(stroke
				(width 0.1)
				(type default)
			)
			(layer "F.Fab")
		)
		(fp_line
			(start -0.12065 -0.2794)
			(end 0.12065 -0.2794)
			(stroke
				(width 0.1)
				(type default)
			)
			(layer "F.Fab")
		)
		(fp_line
			(start 0.12065 -0.2794)
			(end 0.12065 -0.3048)
			(stroke
				(width 0.1)
				(type default)
			)
			(layer "F.Fab")
		)
		(fp_line
			(start 0.12065 -0.3048)
			(end 0.67945 -0.3048)
			(stroke
				(width 0.1)
				(type default)
			)
			(layer "F.Fab")
		)
		(fp_line
			(start 0.67945 -0.3048)
			(end 0.67945 0.3048)
			(stroke
				(width 0.1)
				(type default)
			)
			(layer "F.Fab")
		)
		(fp_line
			(start -0.67945 -0.305054)
			(end -0.12065 -0.305054)
			(stroke
				(width 0.1)
				(type default)
			)
			(layer "F.Fab")
		)
		(fp_line
			(start -0.12065 -0.305054)
			(end -0.12065 -0.2794)
			(stroke
				(width 0.1)
				(type default)
			)
			(layer "F.Fab")
		)
		(pad "1" smd circle
			(at -0.40005 0 270)
			(size 0 0)
			(layers "F.Cu" "F.Mask" "F.Paste")
			(net "P1V25_SERDES_VDDPLL_PEX3")
		)
		(pad "2" smd circle
			(at 0.40005 0 270)
			(size 0 0)
			(layers "F.Cu" "F.Mask" "F.Paste")
			(net "P1V25_SERDES_VDDPLL_PEX3_C5")
		)
	)
	(footprint ""
		(layer "F.Cu")
		(at 265.240008 -259.834634 180)
		(property "Reference" "C3396"
			(at 0 0 180)
			(layer "F.SilkS")
			(hide yes)
			(effects
				(font
					(size 1.27 1.27)
				)
			)
		)
		(property "Value" ""
			(at 0 0 180)
			(layer "F.Fab")
			(effects
				(font
					(size 1.27 1.27)
				)
			)
		)
		(duplicate_pad_numbers_are_jumpers no)
		(fp_line
			(start 1.2954 0.5842)
			(end -1.2954 0.5842)
			(stroke
				(width 0.1524)
				(type default)
			)
			(layer "F.SilkS")
		)
		(fp_line
			(start 1.2954 -0.5842)
			(end 1.2954 0.5842)
			(stroke
				(width 0.1524)
				(type default)
			)
			(layer "F.SilkS")
		)
		(fp_line
			(start -1.2954 0.5842)
			(end -1.2954 -0.5842)
			(stroke
				(width 0.1524)
				(type default)
			)
			(layer "F.SilkS")
		)
		(fp_line
			(start -1.2954 -0.5842)
			(end 1.2954 -0.5842)
			(stroke
				(width 0.1524)
				(type default)
			)
			(layer "F.SilkS")
		)
		(fp_line
			(start 1.1938 0.4064)
			(end 0.8636 0.4064)
			(stroke
				(width 0.1)
				(type default)
			)
			(layer "F.Fab")
		)
		(fp_line
			(start 1.1938 -0.4064)
			(end 1.1938 0.4064)
			(stroke
				(width 0.1)
				(type default)
			)
			(layer "F.Fab")
		)
		(fp_line
			(start 0.8636 0.4572)
			(end -0.8636 0.4572)
			(stroke
				(width 0.1)
				(type default)
			)
			(layer "F.Fab")
		)
		(fp_line
			(start 0.8636 0.4064)
			(end 0.8636 0.4572)
			(stroke
				(width 0.1)
				(type default)
			)
			(layer "F.Fab")
		)
		(fp_line
			(start 0.8636 -0.4064)
			(end 1.1938 -0.4064)
			(stroke
				(width 0.1)
				(type default)
			)
			(layer "F.Fab")
		)
		(fp_line
			(start 0.8636 -0.4572)
			(end 0.8636 -0.4064)
			(stroke
				(width 0.1)
				(type default)
			)
			(layer "F.Fab")
		)
		(fp_line
			(start -0.8636 0.4572)
			(end -0.8636 0.4064)
			(stroke
				(width 0.1)
				(type default)
			)
			(layer "F.Fab")
		)
		(fp_line
			(start -0.8636 0.4064)
			(end -1.1938 0.4064)
			(stroke
				(width 0.1)
				(type default)
			)
			(layer "F.Fab")
		)
		(fp_line
			(start -0.8636 -0.4064)
			(end -0.8636 -0.4572)
			(stroke
				(width 0.1)
				(type default)
			)
			(layer "F.Fab")
		)
		(fp_line
			(start -0.8636 -0.4572)
			(end 0.8636 -0.4572)
			(stroke
				(width 0.1)
				(type default)
			)
			(layer "F.Fab")
		)
		(fp_line
			(start -1.1938 0.4064)
			(end -1.1938 -0.4064)
			(stroke
				(width 0.1)
				(type default)
			)
			(layer "F.Fab")
		)
		(fp_line
			(start -1.1938 -0.4064)
			(end -0.8636 -0.4064)
			(stroke
				(width 0.1)
				(type default)
			)
			(layer "F.Fab")
		)
		(pad "1" smd rect
			(at -0.7366 0 90)
			(size 0.7112 0.8128)
			(layers "F.Cu" "F.Mask" "F.Paste")
			(net "PCEPLL3_VDDA18_PEX2_R")
		)
		(pad "2" smd rect
			(at 0.7366 0 90)
			(size 0.7112 0.8128)
			(layers "F.Cu" "F.Mask" "F.Paste")
			(net "GND")
		)
	)
	(footprint ""
		(layer "F.Cu")
		(at 447.163698 -258.331208 -90)
		(property "Reference" "R6560"
			(at 0 0 270)
			(layer "F.SilkS")
			(hide yes)
			(effects
				(font
					(size 1.27 1.27)
				)
			)
		)
		(property "Value" ""
			(at 0 0 270)
			(layer "F.Fab")
			(effects
				(font
					(size 1.27 1.27)
				)
			)
		)
		(duplicate_pad_numbers_are_jumpers no)
		(fp_line
			(start -0.7874 0.4064)
			(end -0.7874 -0.4064)
			(stroke
				(width 0.1524)
				(type default)
			)
			(layer "F.SilkS")
		)
		(fp_line
			(start 0.7874 0.4064)
			(end -0.7874 0.4064)
			(stroke
				(width 0.1524)
				(type default)
			)
			(layer "F.SilkS")
		)
		(fp_line
			(start -0.7874 -0.4064)
			(end 0.7874 -0.4064)
			(stroke
				(width 0.1524)
				(type default)
			)
			(layer "F.SilkS")
		)
		(fp_line
			(start 0.7874 -0.4064)
			(end 0.7874 0.4064)
			(stroke
				(width 0.1524)
				(type default)
			)
			(layer "F.SilkS")
		)
		(fp_line
			(start -0.67945 0.3048)
			(end -0.67945 -0.305054)
			(stroke
				(width 0.1)
				(type default)
			)
			(layer "F.Fab")
		)
		(fp_line
			(start -0.12065 0.3048)
			(end -0.67945 0.3048)
			(stroke
				(width 0.1)
				(type default)
			)
			(layer "F.Fab")
		)
		(fp_line
			(start 0.120396 0.3048)
			(end 0.120396 0.2794)
			(stroke
				(width 0.1)
				(type default)
			)
			(layer "F.Fab")
		)
		(fp_line
			(start 0.67945 0.3048)
			(end 0.120396 0.3048)
			(stroke
				(width 0.1)
				(type default)
			)
			(layer "F.Fab")
		)
		(fp_line
			(start -0.12065 0.2794)
			(end -0.12065 0.3048)
			(stroke
				(width 0.1)
				(type default)
			)
			(layer "F.Fab")
		)
		(fp_line
			(start 0.120396 0.2794)
			(end -0.12065 0.2794)
			(stroke
				(width 0.1)
				(type default)
			)
			(layer "F.Fab")
		)
		(fp_line
			(start -0.12065 -0.2794)
			(end 0.12065 -0.2794)
			(stroke
				(width 0.1)
				(type default)
			)
			(layer "F.Fab")
		)
		(fp_line
			(start 0.12065 -0.2794)
			(end 0.12065 -0.3048)
			(stroke
				(width 0.1)
				(type default)
			)
			(layer "F.Fab")
		)
		(fp_line
			(start 0.12065 -0.3048)
			(end 0.67945 -0.3048)
			(stroke
				(width 0.1)
				(type default)
			)
			(layer "F.Fab")
		)
		(fp_line
			(start 0.67945 -0.3048)
			(end 0.67945 0.3048)
			(stroke
				(width 0.1)
				(type default)
			)
			(layer "F.Fab")
		)
		(fp_line
			(start -0.67945 -0.305054)
			(end -0.12065 -0.305054)
			(stroke
				(width 0.1)
				(type default)
			)
			(layer "F.Fab")
		)
		(fp_line
			(start -0.12065 -0.305054)
			(end -0.12065 -0.2794)
			(stroke
				(width 0.1)
				(type default)
			)
			(layer "F.Fab")
		)
		(pad "1" smd circle
			(at -0.40005 0 270)
			(size 0 0)
			(layers "F.Cu" "F.Mask" "F.Paste")
			(net "P1V25_SERDES_VDDPLL_PEX3")
		)
		(pad "2" smd circle
			(at 0.40005 0 270)
			(size 0 0)
			(layers "F.Cu" "F.Mask" "F.Paste")
			(net "P1V25_SERDES_VDDPLL_PEX3_C7")
		)
	)
	(footprint ""
		(layer "F.Cu")
		(at 344.612976 -87.25535 180)
		(property "Reference" "R1180"
			(at 0 0 180)
			(layer "F.SilkS")
			(hide yes)
			(effects
				(font
					(size 1.27 1.27)
				)
			)
		)
		(property "Value" ""
			(at 0 0 180)
			(layer "F.Fab")
			(effects
				(font
					(size 1.27 1.27)
				)
			)
		)
		(duplicate_pad_numbers_are_jumpers no)
		(fp_line
			(start -0.7874 -0.4064)
			(end 0.7874 -0.4064)
			(stroke
				(width 0.1524)
				(type default)
			)
			(layer "F.SilkS")
		)
		(fp_line
			(start 0.67945 0.3048)
			(end 0.120396 0.3048)
			(stroke
				(width 0.1)
				(type default)
			)
			(layer "F.Fab")
		)
		(fp_line
			(start 0.67945 -0.3048)
			(end 0.67945 0.3048)
			(stroke
				(width 0.1)
				(type default)
			)
			(layer "F.Fab")
		)
		(fp_line
			(start 0.12065 -0.2794)
			(end 0.12065 -0.3048)
			(stroke
				(width 0.1)
				(type default)
			)
			(layer "F.Fab")
		)
		(fp_line
			(start 0.12065 -0.3048)
			(end 0.67945 -0.3048)
			(stroke
				(width 0.1)
				(type default)
			)
			(layer "F.Fab")
		)
		(fp_line
			(start 0.120396 0.3048)
			(end 0.120396 0.2794)
			(stroke
				(width 0.1)
				(type default)
			)
			(layer "F.Fab")
		)
		(fp_line
			(start 0.120396 0.2794)
			(end -0.12065 0.2794)
			(stroke
				(width 0.1)
				(type default)
			)
			(layer "F.Fab")
		)
		(fp_line
			(start -0.12065 0.3048)
			(end -0.67945 0.3048)
			(stroke
				(width 0.1)
				(type default)
			)
			(layer "F.Fab")
		)
		(fp_line
			(start -0.12065 0.2794)
			(end -0.12065 0.3048)
			(stroke
				(width 0.1)
				(type default)
			)
			(layer "F.Fab")
		)
		(fp_line
			(start -0.12065 -0.2794)
			(end 0.12065 -0.2794)
			(stroke
				(width 0.1)
				(type default)
			)
			(layer "F.Fab")
		)
		(fp_line
			(start -0.12065 -0.305054)
			(end -0.12065 -0.2794)
			(stroke
				(width 0.1)
				(type default)
			)
			(layer "F.Fab")
		)
		(fp_line
			(start -0.67945 0.3048)
			(end -0.67945 -0.305054)
			(stroke
				(width 0.1)
				(type default)
			)
			(layer "F.Fab")
		)
		(fp_line
			(start -0.67945 -0.305054)
			(end -0.12065 -0.305054)
			(stroke
				(width 0.1)
				(type default)
			)
			(layer "F.Fab")
		)
		(pad "1" smd circle
			(at -0.40005 0 180)
			(size 0 0)
			(layers "F.Cu" "F.Mask" "F.Paste")
			(net "CLK_100M_DB800ZL_SSD13_R_DP")
		)
		(pad "2" smd circle
			(at 0.40005 0 180)
			(size 0 0)
			(layers "F.Cu" "F.Mask" "F.Paste")
			(net "CLK_100M_DB800ZL_SSD13_DP")
		)
	)
	(footprint ""
		(layer "F.Cu")
		(at 472.525852 -526.131536 180)
		(property "Reference" "J40_OTH"
			(at -3.2385 -1.402334 0)
			(unlocked yes)
			(layer "B.SilkS")
			(effects
				(font
					(size 0.7874 0.5842)
					(thickness 0.1524)
				)
				(justify mirror)
			)
		)
		(property "Value" ""
			(at 0 0 180)
			(layer "F.Fab")
			(effects
				(font
					(size 1.27 1.27)
				)
			)
		)
		(duplicate_pad_numbers_are_jumpers no)
		(pad "1" thru_hole circle
			(at 0 0 180)
			(size 0.4572 0.4572)
			(drill 0.2032)
			(layers "*.Cu" "*.Mask")
			(remove_unused_layers no)
			(net "Net_9096")
			(clearance 0.127)
			(thermal_gap 0.127)
			(padstack
				(mode front_inner_back)
				(layer "Inner"
					(shape circle)
					(size 0.4572 0.4572)
					(clearance 0.127)
				)
				(layer "B.Cu"
					(shape circle)
					(size 0.508 0.508)
					(clearance 0.1016)
				)
			)
		)
	)
	(footprint ""
		(layer "F.Cu")
		(at 387.06044 -96.1644)
		(property "Reference" "R348"
			(at 0 0 0)
			(layer "F.SilkS")
			(hide yes)
			(effects
				(font
					(size 1.27 1.27)
				)
			)
		)
		(property "Value" ""
			(at 0 0 0)
			(layer "F.Fab")
			(effects
				(font
					(size 1.27 1.27)
				)
			)
		)
		(duplicate_pad_numbers_are_jumpers no)
		(fp_line
			(start -0.7874 -0.4064)
			(end 0.7874 -0.4064)
			(stroke
				(width 0.1524)
				(type default)
			)
			(layer "F.SilkS")
		)
		(fp_line
			(start -0.7874 0.4064)
			(end -0.7874 -0.4064)
			(stroke
				(width 0.1524)
				(type default)
			)
			(layer "F.SilkS")
		)
		(fp_line
			(start 0.7874 -0.4064)
			(end 0.7874 0.4064)
			(stroke
				(width 0.1524)
				(type default)
			)
			(layer "F.SilkS")
		)
		(fp_line
			(start 0.7874 0.4064)
			(end -0.7874 0.4064)
			(stroke
				(width 0.1524)
				(type default)
			)
			(layer "F.SilkS")
		)
		(fp_line
			(start -0.67945 -0.305054)
			(end -0.12065 -0.305054)
			(stroke
				(width 0.1)
				(type default)
			)
			(layer "F.Fab")
		)
		(fp_line
			(start -0.67945 0.3048)
			(end -0.67945 -0.305054)
			(stroke
				(width 0.1)
				(type default)
			)
			(layer "F.Fab")
		)
		(fp_line
			(start -0.12065 -0.305054)
			(end -0.12065 -0.2794)
			(stroke
				(width 0.1)
				(type default)
			)
			(layer "F.Fab")
		)
		(fp_line
			(start -0.12065 -0.2794)
			(end 0.12065 -0.2794)
			(stroke
				(width 0.1)
				(type default)
			)
			(layer "F.Fab")
		)
		(fp_line
			(start -0.12065 0.2794)
			(end -0.12065 0.3048)
			(stroke
				(width 0.1)
				(type default)
			)
			(layer "F.Fab")
		)
		(fp_line
			(start -0.12065 0.3048)
			(end -0.67945 0.3048)
			(stroke
				(width 0.1)
				(type default)
			)
			(layer "F.Fab")
		)
		(fp_line
			(start 0.120396 0.2794)
			(end -0.12065 0.2794)
			(stroke
				(width 0.1)
				(type default)
			)
			(layer "F.Fab")
		)
		(fp_line
			(start 0.120396 0.3048)
			(end 0.120396 0.2794)
			(stroke
				(width 0.1)
				(type default)
			)
			(layer "F.Fab")
		)
		(fp_line
			(start 0.12065 -0.3048)
			(end 0.67945 -0.3048)
			(stroke
				(width 0.1)
				(type default)
			)
			(layer "F.Fab")
		)
		(fp_line
			(start 0.12065 -0.2794)
			(end 0.12065 -0.3048)
			(stroke
				(width 0.1)
				(type default)
			)
			(layer "F.Fab")
		)
		(fp_line
			(start 0.67945 -0.3048)
			(end 0.67945 0.3048)
			(stroke
				(width 0.1)
				(type default)
			)
			(layer "F.Fab")
		)
		(fp_line
			(start 0.67945 0.3048)
			(end 0.120396 0.3048)
			(stroke
				(width 0.1)
				(type default)
			)
			(layer "F.Fab")
		)
		(pad "1" smd circle
			(at -0.40005 0)
			(size 0 0)
			(layers "F.Cu" "F.Mask" "F.Paste")
			(net "PRSNT_NIC6_N")
		)
		(pad "2" smd circle
			(at 0.40005 0)
			(size 0 0)
			(layers "F.Cu" "F.Mask" "F.Paste")
			(net "PRSNTB3_NIC6_N")
		)
	)
	(footprint ""
		(layer "F.Cu")
		(at 136.642856 -170.599862 90)
		(property "Reference" "R1097"
			(at 0 0 90)
			(layer "F.SilkS")
			(hide yes)
			(effects
				(font
					(size 1.27 1.27)
				)
			)
		)
		(property "Value" ""
			(at 0 0 90)
			(layer "F.Fab")
			(effects
				(font
					(size 1.27 1.27)
				)
			)
		)
		(duplicate_pad_numbers_are_jumpers no)
		(fp_line
			(start 0.7874 0.4064)
			(end -0.7874 0.4064)
			(stroke
				(width 0.1524)
				(type default)
			)
			(layer "F.SilkS")
		)
		(fp_line
			(start -0.12065 -0.305054)
			(end -0.12065 -0.2794)
			(stroke
				(width 0.1)
				(type default)
			)
			(layer "F.Fab")
		)
		(fp_line
			(start -0.67945 -0.305054)
			(end -0.12065 -0.305054)
			(stroke
				(width 0.1)
				(type default)
			)
			(layer "F.Fab")
		)
		(fp_line
			(start 0.67945 -0.3048)
			(end 0.67945 0.3048)
			(stroke
				(width 0.1)
				(type default)
			)
			(layer "F.Fab")
		)
		(fp_line
			(start 0.12065 -0.3048)
			(end 0.67945 -0.3048)
			(stroke
				(width 0.1)
				(type default)
			)
			(layer "F.Fab")
		)
		(fp_line
			(start 0.12065 -0.2794)
			(end 0.12065 -0.3048)
			(stroke
				(width 0.1)
				(type default)
			)
			(layer "F.Fab")
		)
		(fp_line
			(start -0.12065 -0.2794)
			(end 0.12065 -0.2794)
			(stroke
				(width 0.1)
				(type default)
			)
			(layer "F.Fab")
		)
		(fp_line
			(start 0.120396 0.2794)
			(end -0.12065 0.2794)
			(stroke
				(width 0.1)
				(type default)
			)
			(layer "F.Fab")
		)
		(fp_line
			(start -0.12065 0.2794)
			(end -0.12065 0.3048)
			(stroke
				(width 0.1)
				(type default)
			)
			(layer "F.Fab")
		)
		(fp_line
			(start 0.67945 0.3048)
			(end 0.120396 0.3048)
			(stroke
				(width 0.1)
				(type default)
			)
			(layer "F.Fab")
		)
		(fp_line
			(start 0.120396 0.3048)
			(end 0.120396 0.2794)
			(stroke
				(width 0.1)
				(type default)
			)
			(layer "F.Fab")
		)
		(fp_line
			(start -0.12065 0.3048)
			(end -0.67945 0.3048)
			(stroke
				(width 0.1)
				(type default)
			)
			(layer "F.Fab")
		)
		(fp_line
			(start -0.67945 0.3048)
			(end -0.67945 -0.305054)
			(stroke
				(width 0.1)
				(type default)
			)
			(layer "F.Fab")
		)
		(pad "1" smd circle
			(at -0.40005 0 90)
			(size 0 0)
			(layers "F.Cu" "F.Mask" "F.Paste")
			(net "CLK_100M_DB2000QL_NIC1_R_DN")
		)
		(pad "2" smd circle
			(at 0.40005 0 90)
			(size 0 0)
			(layers "F.Cu" "F.Mask" "F.Paste")
			(net "CLK_100M_DB2000QL_NIC1_DN")
		)
	)
)
